(kicad_pcb
	(version 20260206)
	(generator "pcbnew")
	(generator_version "10.0")
	(general
		(thickness 1.6)
		(legacy_teardrops no)
	)
	(paper "A4")
	(title_block
		(title "Bryce Canyon_R.DPB_16317-1_OCP.brd")
		(comment 1 "Bryce Canyon / footprints 954-960 of 2099")
	)
	(layers
		(0 "F.Cu" signal "TOP")
		(4 "In1.Cu" signal "L2GND")
		(6 "In2.Cu" signal "L3")
		(8 "In3.Cu" signal "L4VCC")
		(10 "In4.Cu" signal "L5VCC")
		(12 "In5.Cu" signal "L6")
		(14 "In6.Cu" signal "L7GND")
		(2 "B.Cu" signal "BOTTOM")
		(9 "F.Adhes" user "F.Adhesive")
		(11 "B.Adhes" user "B.Adhesive")
		(13 "F.Paste" user "Package Geometry/Pastemask Top")
		(15 "B.Paste" user "Package Geometry/Pastemask Bottom")
		(5 "F.SilkS" user "Ref Des/Silkscreen Top")
		(7 "B.SilkS" user "Ref Des/Silkscreen Bottom")
		(1 "F.Mask" user "Board Geometry/Soldermask Top")
		(3 "B.Mask" user "Board Geometry/Soldermask Bottom")
		(17 "Dwgs.User" user "User.Drawings")
		(19 "Cmts.User" user "User.Comments")
		(21 "Eco1.User" user "User.Eco1")
		(23 "Eco2.User" user "User.Eco2")
		(25 "Edge.Cuts" user "Board Geometry/Outline")
		(27 "Margin" user)
		(31 "F.CrtYd" user "Package Geometry/Place Bound Top")
		(29 "B.CrtYd" user "Package Geometry/Place Bound Bottom")
		(35 "F.Fab" user "Ref Des/Assembly Top")
		(33 "B.Fab" user "Ref Des/Assembly Bottom")
	)
	(footprint ""
		(layer "F.Cu")
		(at 472.6432 -5.6642 90)
		(property "Reference" "R889"
			(at 0 0 90)
			(layer "F.SilkS")
			(hide yes)
			(effects
				(font
					(size 1.27 1.27)
				)
			)
		)
		(property "Value" "4K7R2J-2-GP"
			(at 0.064008 -3.993896 90)
			(unlocked yes)
			(layer "F.Fab")
			(hide yes)
			(effects
				(font
					(size 1.016 1.016)
					(thickness 0.1524)
				)
			)
		)
		(property "Device Type" "R402H16"
			(at 0.064008 -5.517896 90)
			(unlocked yes)
			(layer "F.Fab")
			(hide yes)
			(effects
				(font
					(size 1.016 1.016)
					(thickness 0.1524)
				)
			)
		)
		(duplicate_pad_numbers_are_jumpers no)
		(fp_line
			(start 0.508 -0.9398)
			(end -0.508 -0.9398)
			(stroke
				(width 0.1524)
				(type default)
			)
			(layer "F.SilkS")
		)
		(fp_line
			(start -0.508 -0.9398)
			(end -0.508 0.9398)
			(stroke
				(width 0.1524)
				(type default)
			)
			(layer "F.SilkS")
		)
		(fp_rect
			(start -0.508 0.9398)
			(end 0.508 -0.9398)
			(stroke
				(width 0)
				(type default)
			)
			(fill no)
			(layer "F.CrtYd")
		)
		(fp_rect
			(start -0.508 0.9398)
			(end 0.508 -0.9398)
			(stroke
				(width 0)
				(type default)
			)
			(fill no)
			(layer "F.Fab")
		)
		(pad "1" smd custom
			(at 0 -0.4445 90)
			(size 0.1397 0.1397)
			(layers "F.Cu" "F.Mask" "F.Paste")
			(net "P12V_B")
			(options
				(clearance outline)
				(anchor circle)
			)
			(primitives
				(gr_poly
					(pts
						(arc
							(start -0.1778 -0.2794)
							(mid -0.249642 -0.249642)
							(end -0.2794 -0.1778)
						)
						(arc
							(start -0.2794 0.1778)
							(mid -0.249642 0.249642)
							(end -0.1778 0.2794)
						)
						(arc
							(start 0.1778 0.2794)
							(mid 0.249642 0.249642)
							(end 0.2794 0.1778)
						)
						(arc
							(start 0.2794 -0.1778)
							(mid 0.249642 -0.249642)
							(end 0.1778 -0.2794)
						)
					)
					(width 0)
					(fill yes)
				)
			)
		)
		(pad "2" smd custom
			(at 0 0.4445 90)
			(size 0.1397 0.1397)
			(layers "F.Cu" "F.Mask" "F.Paste")
			(net "SW_HDD_R35")
			(options
				(clearance outline)
				(anchor circle)
			)
			(primitives
				(gr_poly
					(pts
						(arc
							(start -0.1778 -0.2794)
							(mid -0.249642 -0.249642)
							(end -0.2794 -0.1778)
						)
						(arc
							(start -0.2794 0.1778)
							(mid -0.249642 0.249642)
							(end -0.1778 0.2794)
						)
						(arc
							(start 0.1778 0.2794)
							(mid 0.249642 0.249642)
							(end 0.2794 0.1778)
						)
						(arc
							(start 0.2794 -0.1778)
							(mid 0.249642 -0.249642)
							(end 0.1778 -0.2794)
						)
					)
					(width 0)
					(fill yes)
				)
			)
		)
	)
	(footprint ""
		(layer "F.Cu")
		(at 24.704802 -229.49535 -90)
		(property "Reference" "C623"
			(at 0 0 270)
			(layer "F.SilkS")
			(hide yes)
			(effects
				(font
					(size 1.27 1.27)
				)
			)
		)
		(property "Value" "SC1U16V3KX-5GP"
			(at 0 -2.8194 270)
			(unlocked yes)
			(layer "F.Fab")
			(hide yes)
			(effects
				(font
					(size 1.016 1.016)
					(thickness 0.1524)
				)
			)
		)
		(property "Device Type" "C603H36"
			(at 0 -4.3434 270)
			(unlocked yes)
			(layer "F.Fab")
			(hide yes)
			(effects
				(font
					(size 1.016 1.016)
					(thickness 0.1524)
				)
			)
		)
		(duplicate_pad_numbers_are_jumpers no)
		(fp_line
			(start 0.508 0)
			(end -0.508 0)
			(stroke
				(width 0.2032)
				(type default)
			)
			(layer "F.SilkS")
		)
		(fp_rect
			(start -0.5842 1.3335)
			(end 0.5842 -1.3335)
			(stroke
				(width 0)
				(type default)
			)
			(fill no)
			(layer "F.CrtYd")
		)
		(fp_rect
			(start -0.5842 1.3335)
			(end 0.5842 -1.3335)
			(stroke
				(width 0)
				(type default)
			)
			(fill no)
			(layer "F.Fab")
		)
		(pad "1" smd custom
			(at 0 -0.762 270)
			(size 0.2159 0.2159)
			(layers "F.Cu" "F.Mask" "F.Paste")
			(net "P5V_B_1_EN_R")
			(options
				(clearance outline)
				(anchor circle)
			)
			(primitives
				(gr_poly
					(pts
						(arc
							(start -0.3302 -0.4318)
							(mid -0.402042 -0.402042)
							(end -0.4318 -0.3302)
						)
						(arc
							(start -0.4318 0.3302)
							(mid -0.402042 0.402042)
							(end -0.3302 0.4318)
						)
						(arc
							(start 0.3302 0.4318)
							(mid 0.402042 0.402042)
							(end 0.4318 0.3302)
						)
						(arc
							(start 0.4318 -0.3302)
							(mid 0.402042 -0.402042)
							(end 0.3302 -0.4318)
						)
					)
					(width 0)
					(fill yes)
				)
			)
		)
		(pad "2" smd custom
			(at 0 0.762 270)
			(size 0.2159 0.2159)
			(layers "F.Cu" "F.Mask" "F.Paste")
			(net "GND")
			(options
				(clearance outline)
				(anchor circle)
			)
			(primitives
				(gr_poly
					(pts
						(arc
							(start -0.3302 -0.4318)
							(mid -0.402042 -0.402042)
							(end -0.4318 -0.3302)
						)
						(arc
							(start -0.4318 0.3302)
							(mid -0.402042 0.402042)
							(end -0.3302 0.4318)
						)
						(arc
							(start 0.3302 0.4318)
							(mid 0.402042 0.402042)
							(end 0.4318 0.3302)
						)
						(arc
							(start 0.4318 -0.3302)
							(mid 0.402042 -0.402042)
							(end 0.3302 -0.4318)
						)
					)
					(width 0)
					(fill yes)
				)
			)
		)
	)
	(footprint ""
		(layer "F.Cu")
		(at 335.788 -128.651 180)
		(property "Reference" "R495"
			(at 0 0 180)
			(layer "F.SilkS")
			(hide yes)
			(effects
				(font
					(size 1.27 1.27)
				)
			)
		)
		(property "Value" "0R2J-2-GP"
			(at 0.064008 -3.993896 180)
			(unlocked yes)
			(layer "F.Fab")
			(hide yes)
			(effects
				(font
					(size 1.016 1.016)
					(thickness 0.1524)
				)
			)
		)
		(property "Device Type" "R402H16"
			(at 0.064008 -5.517896 180)
			(unlocked yes)
			(layer "F.Fab")
			(hide yes)
			(effects
				(font
					(size 1.016 1.016)
					(thickness 0.1524)
				)
			)
		)
		(duplicate_pad_numbers_are_jumpers no)
		(fp_line
			(start 0.508 -0.9398)
			(end -0.508 -0.9398)
			(stroke
				(width 0.1524)
				(type default)
			)
			(layer "F.SilkS")
		)
		(fp_line
			(start -0.508 -0.9398)
			(end -0.508 0.9398)
			(stroke
				(width 0.1524)
				(type default)
			)
			(layer "F.SilkS")
		)
		(fp_rect
			(start -0.508 0.9398)
			(end 0.508 -0.9398)
			(stroke
				(width 0)
				(type default)
			)
			(fill no)
			(layer "F.CrtYd")
		)
		(fp_rect
			(start -0.508 0.9398)
			(end 0.508 -0.9398)
			(stroke
				(width 0)
				(type default)
			)
			(fill no)
			(layer "F.Fab")
		)
		(pad "1" smd custom
			(at 0 -0.4445 180)
			(size 0.1397 0.1397)
			(layers "F.Cu" "F.Mask" "F.Paste")
			(net "DRIVE_B_18_PWR")
			(options
				(clearance outline)
				(anchor circle)
			)
			(primitives
				(gr_poly
					(pts
						(arc
							(start -0.1778 -0.2794)
							(mid -0.249642 -0.249642)
							(end -0.2794 -0.1778)
						)
						(arc
							(start -0.2794 0.1778)
							(mid -0.249642 0.249642)
							(end -0.1778 0.2794)
						)
						(arc
							(start 0.1778 0.2794)
							(mid 0.249642 0.249642)
							(end 0.2794 0.1778)
						)
						(arc
							(start 0.2794 -0.1778)
							(mid 0.249642 -0.249642)
							(end 0.1778 -0.2794)
						)
					)
					(width 0)
					(fill yes)
				)
			)
		)
		(pad "2" smd custom
			(at 0 0.4445 180)
			(size 0.1397 0.1397)
			(layers "F.Cu" "F.Mask" "F.Paste")
			(net "SW_PWR_R_HDD18")
			(options
				(clearance outline)
				(anchor circle)
			)
			(primitives
				(gr_poly
					(pts
						(arc
							(start -0.1778 -0.2794)
							(mid -0.249642 -0.249642)
							(end -0.2794 -0.1778)
						)
						(arc
							(start -0.2794 0.1778)
							(mid -0.249642 0.249642)
							(end -0.1778 0.2794)
						)
						(arc
							(start 0.1778 0.2794)
							(mid 0.249642 0.249642)
							(end 0.2794 0.1778)
						)
						(arc
							(start 0.2794 -0.1778)
							(mid 0.249642 -0.249642)
							(end 0.1778 -0.2794)
						)
					)
					(width 0)
					(fill yes)
				)
			)
		)
	)
	(footprint ""
		(layer "F.Cu")
		(at 33.3248 -293.799768)
		(property "Reference" ""
			(at 0 0 0)
			(layer "F.SilkS")
			(hide yes)
			(effects
				(font
					(size 1.27 1.27)
				)
			)
		)
		(property "Value" "*"
			(at -8.398764 -8.057642 0)
			(unlocked yes)
			(layer "F.Fab")
			(hide yes)
			(effects
				(font
					(size 1.016 1.016)
					(thickness 0.1524)
				)
			)
		)
		(duplicate_pad_numbers_are_jumpers no)
		(fp_poly
			(pts
				(arc
					(start 7.3152 0)
					(mid 0 7.3152)
					(end -7.3152 0)
				)
				(arc
					(start -7.3152 -5.9944)
					(mid 0 -13.3096)
					(end 7.3152 -5.9944)
				)
			)
			(stroke
				(width 0)
				(type default)
			)
			(fill no)
			(layer "B.CrtYd")
		)
		(fp_poly
			(pts
				(arc
					(start 7.3152 0)
					(mid 0 7.3152)
					(end -7.3152 0)
				)
				(arc
					(start -7.3152 -5.9944)
					(mid 0 -13.3096)
					(end 7.3152 -5.9944)
				)
			)
			(stroke
				(width 0)
				(type default)
			)
			(fill no)
			(layer "F.CrtYd")
		)
		(fp_poly
			(pts
				(arc
					(start 7.3152 0)
					(mid 0 7.3152)
					(end -7.3152 0)
				)
				(arc
					(start -7.3152 -5.9944)
					(mid 0 -13.3096)
					(end 7.3152 -5.9944)
				)
			)
			(stroke
				(width 0)
				(type default)
			)
			(fill no)
			(layer "B.Fab")
		)
		(fp_poly
			(pts
				(arc
					(start 7.3152 0)
					(mid 0 7.3152)
					(end -7.3152 0)
				)
				(arc
					(start -7.3152 -5.9944)
					(mid 0 -13.3096)
					(end 7.3152 -5.9944)
				)
			)
			(stroke
				(width 0)
				(type default)
			)
			(fill no)
			(layer "F.Fab")
		)
		(pad "1" thru_hole oval
			(at 0 0)
			(size 14.0208 20.0152)
			(drill 0.0254
				(offset 0 -2.9972)
			)
			(layers "*.Cu" "*.Mask")
			(remove_unused_layers no)
			(net "Net_12")
			(clearance -1.002284)
			(thermal_gap 0.1524)
			(padstack
				(mode front_inner_back)
				(layer "Inner"
					(shape custom)
					(size 2.928012 2.928012)
					(options
						(anchor circle)
					)
					(primitives
						(gr_poly
							(pts
								(arc
									(start 4.571746 -2.084324)
									(mid 0.000333 7.430372)
									(end -4.571492 -2.084324)
								)
								(arc
									(start -4.571492 -2.084324)
									(mid -3.570296 -3.611977)
									(end -2.875026 -5.30098)
								)
								(arc
									(start -2.875026 -5.30098)
									(mid 0.000217 -7.43089)
									(end 2.87528 -5.30098)
								)
								(arc
									(start 2.87528 -5.30098)
									(mid 3.570511 -3.611956)
									(end 4.571746 -2.084324)
								)
							)
							(width 0)
							(fill yes)
						)
					)
					(clearance 0.1524)
				)
				(layer "B.Cu"
					(shape oval)
					(size 14.0208 20.0152)
					(offset 0 -2.9972)
					(clearance -1.002284)
				)
			)
		)
		(zone
			(layers "F.Cu" "B.Cu" "In1.Cu" "In2.Cu" "In3.Cu" "In4.Cu" "In5.Cu" "In6.Cu")
			(hatch none 0.5)
			(connect_pads
				(clearance 0)
			)
			(min_thickness 0.25)
			(keepout
				(tracks not_allowed)
				(vias allowed)
				(pads allowed)
				(copperpour not_allowed)
				(footprints allowed)
			)
			(placement
				(enabled no)
				(sheetname "")
			)
			(fill
				(thermal_gap 0.5)
				(thermal_bridge_width 0.5)
				(island_removal_mode 0)
			)
			(polygon
				(pts
					(arc
						(start 26.3144 -299.794168)
						(mid 33.3248 -306.804568)
						(end 40.3352 -299.794168)
					)
					(arc
						(start 40.3352 -293.799768)
						(mid 33.3248 -286.789368)
						(end 26.3144 -293.799768)
					)
				)
			)
		)
	)
	(footprint ""
		(layer "F.Cu")
		(at 206.970122 -105.154984)
		(property "Reference" "TC4"
			(at 0 0 0)
			(layer "F.SilkS")
			(hide yes)
			(effects
				(font
					(size 1.27 1.27)
				)
			)
		)
		(property "Value" "SE270U16VM-8-GP"
			(at -4.5974 -2.54 0)
			(unlocked yes)
			(layer "F.Fab")
			(hide yes)
			(effects
				(font
					(size 1.016 1.016)
					(thickness 0.1524)
				)
			)
		)
		(property "Device Type" "SE361416H394"
			(at -4.5974 -4.064 0)
			(unlocked yes)
			(layer "F.Fab")
			(hide yes)
			(effects
				(font
					(size 1.016 1.016)
					(thickness 0.1524)
				)
			)
		)
		(duplicate_pad_numbers_are_jumpers no)
		(fp_line
			(start -3.556 -3.4163)
			(end -2.3622 -4.6101)
			(stroke
				(width 0.1524)
				(type default)
			)
			(layer "F.SilkS")
		)
		(fp_line
			(start -3.556 4.6101)
			(end -3.556 -3.4163)
			(stroke
				(width 0.1524)
				(type default)
			)
			(layer "F.SilkS")
		)
		(fp_line
			(start -2.3622 -4.6101)
			(end 2.3622 -4.6101)
			(stroke
				(width 0.1524)
				(type default)
			)
			(layer "F.SilkS")
		)
		(fp_line
			(start 2.3622 -4.6101)
			(end 3.556 -3.4163)
			(stroke
				(width 0.1524)
				(type default)
			)
			(layer "F.SilkS")
		)
		(fp_line
			(start 3.556 -3.4163)
			(end 3.556 4.6101)
			(stroke
				(width 0.1524)
				(type default)
			)
			(layer "F.SilkS")
		)
		(fp_line
			(start 3.556 4.6101)
			(end -3.556 4.6101)
			(stroke
				(width 0.1524)
				(type default)
			)
			(layer "F.SilkS")
		)
		(fp_rect
			(start -3.302 3.6449)
			(end 3.302 -3.6449)
			(stroke
				(width 0)
				(type default)
			)
			(fill no)
			(layer "F.CrtYd")
		)
		(fp_poly
			(pts
				(xy 3.81 4.6863) (xy 3.81 -3.4925) (xy 3.302 -3.4925) (xy 3.302 3.6449) (xy -3.302 3.6449) (xy -3.302 -3.6449)
				(xy 3.302 -3.6449) (xy 3.302 -3.5052) (xy 3.81 -3.5052) (xy 3.81 -4.6863) (xy -3.81 -4.6863) (xy -3.81 4.6863)
			)
			(stroke
				(width 0)
				(type default)
			)
			(fill no)
			(layer "F.CrtYd")
		)
		(fp_rect
			(start -3.81 4.6863)
			(end 3.81 -4.6863)
			(stroke
				(width 0)
				(type default)
			)
			(fill no)
			(layer "F.Fab")
		)
		(pad "1" smd rect
			(at 0 -2.574036)
			(size 1.4224 3.556)
			(layers "F.Cu" "F.Mask" "F.Paste")
			(net "P12V_B")
		)
		(pad "2" smd rect
			(at 0 2.574036)
			(size 1.4224 3.556)
			(layers "F.Cu" "F.Mask" "F.Paste")
			(net "GND")
		)
	)
	(footprint ""
		(layer "F.Cu")
		(at 134.196836 -363.405166 180)
		(property "Reference" "C527"
			(at 0 0 180)
			(layer "F.SilkS")
			(hide yes)
			(effects
				(font
					(size 1.27 1.27)
				)
			)
		)
		(property "Value" "SC1U25V3KX-GP"
			(at 0 -2.8194 180)
			(unlocked yes)
			(layer "F.Fab")
			(hide yes)
			(effects
				(font
					(size 1.016 1.016)
					(thickness 0.1524)
				)
			)
		)
		(property "Device Type" "C603H36"
			(at 0 -4.3434 180)
			(unlocked yes)
			(layer "F.Fab")
			(hide yes)
			(effects
				(font
					(size 1.016 1.016)
					(thickness 0.1524)
				)
			)
		)
		(duplicate_pad_numbers_are_jumpers no)
		(fp_line
			(start 0.508 0)
			(end -0.508 0)
			(stroke
				(width 0.2032)
				(type default)
			)
			(layer "F.SilkS")
		)
		(fp_rect
			(start -0.5842 1.3335)
			(end 0.5842 -1.3335)
			(stroke
				(width 0)
				(type default)
			)
			(fill no)
			(layer "F.CrtYd")
		)
		(fp_rect
			(start -0.5842 1.3335)
			(end 0.5842 -1.3335)
			(stroke
				(width 0)
				(type default)
			)
			(fill no)
			(layer "F.Fab")
		)
		(pad "1" smd custom
			(at 0 -0.762 180)
			(size 0.2159 0.2159)
			(layers "F.Cu" "F.Mask" "F.Paste")
			(net "P12V_FAN1")
			(options
				(clearance outline)
				(anchor circle)
			)
			(primitives
				(gr_poly
					(pts
						(arc
							(start -0.3302 -0.4318)
							(mid -0.402042 -0.402042)
							(end -0.4318 -0.3302)
						)
						(arc
							(start -0.4318 0.3302)
							(mid -0.402042 0.402042)
							(end -0.3302 0.4318)
						)
						(arc
							(start 0.3302 0.4318)
							(mid 0.402042 0.402042)
							(end 0.4318 0.3302)
						)
						(arc
							(start 0.4318 -0.3302)
							(mid 0.402042 -0.402042)
							(end 0.3302 -0.4318)
						)
					)
					(width 0)
					(fill yes)
				)
			)
		)
		(pad "2" smd custom
			(at 0 0.762 180)
			(size 0.2159 0.2159)
			(layers "F.Cu" "F.Mask" "F.Paste")
			(net "GND")
			(options
				(clearance outline)
				(anchor circle)
			)
			(primitives
				(gr_poly
					(pts
						(arc
							(start -0.3302 -0.4318)
							(mid -0.402042 -0.402042)
							(end -0.4318 -0.3302)
						)
						(arc
							(start -0.4318 0.3302)
							(mid -0.402042 0.402042)
							(end -0.3302 0.4318)
						)
						(arc
							(start 0.3302 0.4318)
							(mid 0.402042 0.402042)
							(end 0.4318 0.3302)
						)
						(arc
							(start 0.4318 -0.3302)
							(mid 0.402042 -0.402042)
							(end 0.3302 -0.4318)
						)
					)
					(width 0)
					(fill yes)
				)
			)
		)
	)
	(footprint ""
		(layer "F.Cu")
		(at 289.080448 -347.541342 180)
		(property "Reference" "R1083"
			(at 0 0 180)
			(layer "F.SilkS")
			(hide yes)
			(effects
				(font
					(size 1.27 1.27)
				)
			)
		)
		(property "Value" "0R2J-2-GP"
			(at 0.064008 -3.993896 180)
			(unlocked yes)
			(layer "F.Fab")
			(hide yes)
			(effects
				(font
					(size 1.016 1.016)
					(thickness 0.1524)
				)
			)
		)
		(property "Device Type" "R402H16"
			(at 0.064008 -5.517896 180)
			(unlocked yes)
			(layer "F.Fab")
			(hide yes)
			(effects
				(font
					(size 1.016 1.016)
					(thickness 0.1524)
				)
			)
		)
		(duplicate_pad_numbers_are_jumpers no)
		(fp_line
			(start 0.508 -0.9398)
			(end -0.508 -0.9398)
			(stroke
				(width 0.1524)
				(type default)
			)
			(layer "F.SilkS")
		)
		(fp_line
			(start -0.508 -0.9398)
			(end -0.508 0.9398)
			(stroke
				(width 0.1524)
				(type default)
			)
			(layer "F.SilkS")
		)
		(fp_rect
			(start -0.508 0.9398)
			(end 0.508 -0.9398)
			(stroke
				(width 0)
				(type default)
			)
			(fill no)
			(layer "F.CrtYd")
		)
		(fp_rect
			(start -0.508 0.9398)
			(end 0.508 -0.9398)
			(stroke
				(width 0)
				(type default)
			)
			(fill no)
			(layer "F.Fab")
		)
		(pad "1" smd custom
			(at 0 -0.4445 180)
			(size 0.1397 0.1397)
			(layers "F.Cu" "F.Mask" "F.Paste")
			(net "GND")
			(options
				(clearance outline)
				(anchor circle)
			)
			(primitives
				(gr_poly
					(pts
						(arc
							(start -0.1778 -0.2794)
							(mid -0.249642 -0.249642)
							(end -0.2794 -0.1778)
						)
						(arc
							(start -0.2794 0.1778)
							(mid -0.249642 0.249642)
							(end -0.1778 0.2794)
						)
						(arc
							(start 0.1778 0.2794)
							(mid 0.249642 0.249642)
							(end 0.2794 0.1778)
						)
						(arc
							(start 0.2794 -0.1778)
							(mid 0.249642 -0.249642)
							(end 0.1778 -0.2794)
						)
					)
					(width 0)
					(fill yes)
				)
			)
		)
		(pad "2" smd custom
			(at 0 0.4445 180)
			(size 0.1397 0.1397)
			(layers "F.Cu" "F.Mask" "F.Paste")
			(net "MAX31790_B_WD_ST")
			(options
				(clearance outline)
				(anchor circle)
			)
			(primitives
				(gr_poly
					(pts
						(arc
							(start -0.1778 -0.2794)
							(mid -0.249642 -0.249642)
							(end -0.2794 -0.1778)
						)
						(arc
							(start -0.2794 0.1778)
							(mid -0.249642 0.249642)
							(end -0.1778 0.2794)
						)
						(arc
							(start 0.1778 0.2794)
							(mid 0.249642 0.249642)
							(end 0.2794 0.1778)
						)
						(arc
							(start 0.2794 -0.1778)
							(mid 0.249642 -0.249642)
							(end 0.1778 -0.2794)
						)
					)
					(width 0)
					(fill yes)
				)
			)
		)
	)
)
